# T6G (Grand Teton) — schematic parts with pin connectivity, parts 807–911 of 8303; source: Cadence DE-HDL packaged netlist (pstxprt.dat, pstxnet.dat, pstchip.dat)

C806  Q_CAP_DIFFBUS  DIFF BUS_0.22UF 6.3V 20% X6S  pkg C0201  page 65 : 1 = P5E_CPU1_P0_TX_C_DN<15> ; 2 = P5E_CPU1_P0_TX_DN<15>
C807  Q_CAP_DIFFBUS  DIFF BUS_0.22UF 6.3V 20% X6S  pkg C0201  page 65 : 1 = P5E_CPU1_P0_TX_C_DP<15> ; 2 = P5E_CPU1_P0_TX_DP<15>
C808  Q_CAP_DIFFBUS  DIFF BUS_0.22UF 6.3V 20% X6S  pkg C0201  page 65 : 1 = P5E_CPU1_P0_TX_C_DN<14> ; 2 = P5E_CPU1_P0_TX_DN<14>
C809  Q_CAP_DIFFBUS  DIFF BUS_0.22UF 6.3V 20% X6S  pkg C0201  page 65 : 1 = P5E_CPU1_P0_TX_C_DP<14> ; 2 = P5E_CPU1_P0_TX_DP<14>
C810  Q_CAP_DIFFBUS  DIFF BUS_0.22UF 6.3V 20% X6S  pkg C0201  page 65 : 1 = P5E_CPU1_P0_TX_C_DN<13> ; 2 = P5E_CPU1_P0_TX_DN<13>
C811  Q_CAP_DIFFBUS  DIFF BUS_0.22UF 6.3V 20% X6S  pkg C0201  page 65 : 1 = P5E_CPU1_P0_TX_C_DP<13> ; 2 = P5E_CPU1_P0_TX_DP<13>
C812  Q_CAP_DIFFBUS  DIFF BUS_0.22UF 6.3V 20% X6S  pkg C0201  page 65 : 1 = P5E_CPU1_P0_TX_C_DN<12> ; 2 = P5E_CPU1_P0_TX_DN<12>
C813  Q_CAP_DIFFBUS  DIFF BUS_0.22UF 6.3V 20% X6S  pkg C0201  page 65 : 1 = P5E_CPU1_P0_TX_C_DP<12> ; 2 = P5E_CPU1_P0_TX_DP<12>
C814  Q_CAP_DIFFBUS  DIFF BUS_0.22UF 6.3V 20% X6S  pkg C0201  page 65 : 1 = P5E_CPU1_P0_TX_C_DN<11> ; 2 = P5E_CPU1_P0_TX_DN<11>
C815  Q_CAP_DIFFBUS  DIFF BUS_0.22UF 6.3V 20% X6S  pkg C0201  page 65 : 1 = P5E_CPU1_P0_TX_C_DP<11> ; 2 = P5E_CPU1_P0_TX_DP<11>
C816  Q_CAP_DIFFBUS  DIFF BUS_0.22UF 6.3V 20% X6S  pkg C0201  page 65 : 1 = P5E_CPU1_P0_TX_C_DN<10> ; 2 = P5E_CPU1_P0_TX_DN<10>
C817  Q_CAP_DIFFBUS  DIFF BUS_0.22UF 6.3V 20% X6S  pkg C0201  page 65 : 1 = P5E_CPU1_P0_TX_C_DP<10> ; 2 = P5E_CPU1_P0_TX_DP<10>
C818  Q_CAP_DIFFBUS  DIFF BUS_0.22UF 6.3V 20% X6S  pkg C0201  page 65 : 1 = P5E_CPU1_P0_TX_C_DN<9> ; 2 = P5E_CPU1_P0_TX_DN<9>
C819  Q_CAP_DIFFBUS  DIFF BUS_0.22UF 6.3V 20% X6S  pkg C0201  page 65 : 1 = P5E_CPU1_P0_TX_C_DP<9> ; 2 = P5E_CPU1_P0_TX_DP<9>
C820  Q_CAP_DIFFBUS  DIFF BUS_0.22UF 6.3V 20% X6S  pkg C0201  page 65 : 1 = P5E_CPU1_P0_TX_C_DN<8> ; 2 = P5E_CPU1_P0_TX_DN<8>
C821  Q_CAP_DIFFBUS  DIFF BUS_0.22UF 6.3V 20% X6S  pkg C0201  page 65 : 1 = P5E_CPU1_P0_TX_C_DP<8> ; 2 = P5E_CPU1_P0_TX_DP<8>
C822  Q_CAP_DIFFBUS  DIFF BUS_0.22UF 6.3V 20% X6S  pkg C0201  page 65 : 1 = P5E_CPU1_P0_TX_C_DN<7> ; 2 = P5E_CPU1_P0_TX_DN<7>
C823  Q_CAP_DIFFBUS  DIFF BUS_0.22UF 6.3V 20% X6S  pkg C0201  page 65 : 1 = P5E_CPU1_P0_TX_C_DP<7> ; 2 = P5E_CPU1_P0_TX_DP<7>
C824  Q_CAP_DIFFBUS  DIFF BUS_0.22UF 6.3V 20% X6S  pkg C0201  page 65 : 1 = P5E_CPU1_P0_TX_C_DN<6> ; 2 = P5E_CPU1_P0_TX_DN<6>
C825  Q_CAP_DIFFBUS  DIFF BUS_0.22UF 6.3V 20% X6S  pkg C0201  page 65 : 1 = P5E_CPU1_P0_TX_C_DP<6> ; 2 = P5E_CPU1_P0_TX_DP<6>
C826  Q_CAP_DIFFBUS  DIFF BUS_0.22UF 6.3V 20% X6S  pkg C0201  page 65 : 1 = P5E_CPU1_P0_TX_C_DN<5> ; 2 = P5E_CPU1_P0_TX_DN<5>
C827  Q_CAP_DIFFBUS  DIFF BUS_0.22UF 6.3V 20% X6S  pkg C0201  page 65 : 1 = P5E_CPU1_P0_TX_C_DP<5> ; 2 = P5E_CPU1_P0_TX_DP<5>
C828  Q_CAP_DIFFBUS  DIFF BUS_0.22UF 6.3V 20% X6S  pkg C0201  page 65 : 1 = P5E_CPU1_P0_TX_C_DN<4> ; 2 = P5E_CPU1_P0_TX_DN<4>
C829  Q_CAP_DIFFBUS  DIFF BUS_0.22UF 6.3V 20% X6S  pkg C0201  page 65 : 1 = P5E_CPU1_P0_TX_C_DP<4> ; 2 = P5E_CPU1_P0_TX_DP<4>
C830  Q_CAP_DIFFBUS  DIFF BUS_0.22UF 6.3V 20% X6S  pkg C0201  page 65 : 1 = P5E_CPU1_P0_TX_C_DN<3> ; 2 = P5E_CPU1_P0_TX_DN<3>
C831  Q_CAP_DIFFBUS  DIFF BUS_0.22UF 6.3V 20% X6S  pkg C0201  page 65 : 1 = P5E_CPU1_P0_TX_C_DP<3> ; 2 = P5E_CPU1_P0_TX_DP<3>
C832  Q_CAP_DIFFBUS  DIFF BUS_0.22UF 6.3V 20% X6S  pkg C0201  page 65 : 1 = P5E_CPU1_P0_TX_C_DN<2> ; 2 = P5E_CPU1_P0_TX_DN<2>
C833  Q_CAP_DIFFBUS  DIFF BUS_0.22UF 6.3V 20% X6S  pkg C0201  page 65 : 1 = P5E_CPU1_P0_TX_C_DP<2> ; 2 = P5E_CPU1_P0_TX_DP<2>
C834  Q_CAP_DIFFBUS  DIFF BUS_0.22UF 6.3V 20% X6S  pkg C0201  page 65 : 1 = P5E_CPU1_P0_TX_C_DN<1> ; 2 = P5E_CPU1_P0_TX_DN<1>
C835  Q_CAP_DIFFBUS  DIFF BUS_0.22UF 6.3V 20% X6S  pkg C0201  page 65 : 1 = P5E_CPU1_P0_TX_C_DP<1> ; 2 = P5E_CPU1_P0_TX_DP<1>
C836  Q_CAP_DIFFBUS  DIFF BUS_0.22UF 6.3V 20% X6S  pkg C0201  page 65 : 1 = P5E_CPU1_P0_TX_C_DN<0> ; 2 = P5E_CPU1_P0_TX_DN<0>
C837  Q_CAP_DIFFBUS  DIFF BUS_0.22UF 6.3V 20% X6S  pkg C0201  page 65 : 1 = P5E_CPU1_P0_TX_C_DP<0> ; 2 = P5E_CPU1_P0_TX_DP<0>
C838  Q_CAP_DIFFBUS  DIFF BUS_0.22UF 6.3V 20% X6S  pkg C0201  page 64 : 1 = P5E_CPU0_P2_TX_C_DN<15> ; 2 = P5E_CPU0_P2_TX_DN<15>
C839  Q_CAP_DIFFBUS  DIFF BUS_0.22UF 6.3V 20% X6S  pkg C0201  page 64 : 1 = P5E_CPU0_P2_TX_C_DP<15> ; 2 = P5E_CPU0_P2_TX_DP<15>
C840  Q_CAP_DIFFBUS  DIFF BUS_0.22UF 6.3V 20% X6S  pkg C0201  page 64 : 1 = P5E_CPU0_P2_TX_C_DN<14> ; 2 = P5E_CPU0_P2_TX_DN<14>
C841  Q_CAP_DIFFBUS  DIFF BUS_0.22UF 6.3V 20% X6S  pkg C0201  page 64 : 1 = P5E_CPU0_P2_TX_C_DP<14> ; 2 = P5E_CPU0_P2_TX_DP<14>
C842  Q_CAP_DIFFBUS  DIFF BUS_0.22UF 6.3V 20% X6S  pkg C0201  page 64 : 1 = P5E_CPU0_P2_TX_C_DN<13> ; 2 = P5E_CPU0_P2_TX_DN<13>
C843  Q_CAP_DIFFBUS  DIFF BUS_0.22UF 6.3V 20% X6S  pkg C0201  page 64 : 1 = P5E_CPU0_P2_TX_C_DP<13> ; 2 = P5E_CPU0_P2_TX_DP<13>
C844  Q_CAP_DIFFBUS  DIFF BUS_0.22UF 6.3V 20% X6S  pkg C0201  page 64 : 1 = P5E_CPU0_P2_TX_C_DN<12> ; 2 = P5E_CPU0_P2_TX_DN<12>
C845  Q_CAP_DIFFBUS  DIFF BUS_0.22UF 6.3V 20% X6S  pkg C0201  page 64 : 1 = P5E_CPU0_P2_TX_C_DP<12> ; 2 = P5E_CPU0_P2_TX_DP<12>
C846  Q_CAP_DIFFBUS  DIFF BUS_0.22UF 6.3V 20% X6S  pkg C0201  page 64 : 1 = P5E_CPU0_P2_TX_C_DN<11> ; 2 = P5E_CPU0_P2_TX_DN<11>
C847  Q_CAP_DIFFBUS  DIFF BUS_0.22UF 6.3V 20% X6S  pkg C0201  page 64 : 1 = P5E_CPU0_P2_TX_C_DP<11> ; 2 = P5E_CPU0_P2_TX_DP<11>
C848  Q_CAP_DIFFBUS  DIFF BUS_0.22UF 6.3V 20% X6S  pkg C0201  page 64 : 1 = P5E_CPU0_P2_TX_C_DN<10> ; 2 = P5E_CPU0_P2_TX_DN<10>
C849  Q_CAP_DIFFBUS  DIFF BUS_0.22UF 6.3V 20% X6S  pkg C0201  page 64 : 1 = P5E_CPU0_P2_TX_C_DP<10> ; 2 = P5E_CPU0_P2_TX_DP<10>
C850  Q_CAP_DIFFBUS  DIFF BUS_0.22UF 6.3V 20% X6S  pkg C0201  page 64 : 1 = P5E_CPU0_P2_TX_C_DN<9> ; 2 = P5E_CPU0_P2_TX_DN<9>
C851  Q_CAP_DIFFBUS  DIFF BUS_0.22UF 6.3V 20% X6S  pkg C0201  page 64 : 1 = P5E_CPU0_P2_TX_C_DP<9> ; 2 = P5E_CPU0_P2_TX_DP<9>
C852  Q_CAP_DIFFBUS  DIFF BUS_0.22UF 6.3V 20% X6S  pkg C0201  page 64 : 1 = P5E_CPU0_P2_TX_C_DN<8> ; 2 = P5E_CPU0_P2_TX_DN<8>
C853  Q_CAP_DIFFBUS  DIFF BUS_0.22UF 6.3V 20% X6S  pkg C0201  page 64 : 1 = P5E_CPU0_P2_TX_C_DP<8> ; 2 = P5E_CPU0_P2_TX_DP<8>
C854  Q_CAP_DIFFBUS  DIFF BUS_0.22UF 6.3V 20% X6S  pkg C0201  page 64 : 1 = P5E_CPU0_P2_TX_C_DN<7> ; 2 = P5E_CPU0_P2_TX_DN<7>
C855  Q_CAP_DIFFBUS  DIFF BUS_0.22UF 6.3V 20% X6S  pkg C0201  page 64 : 1 = P5E_CPU0_P2_TX_C_DP<7> ; 2 = P5E_CPU0_P2_TX_DP<7>
C856  Q_CAP_DIFFBUS  DIFF BUS_0.22UF 6.3V 20% X6S  pkg C0201  page 64 : 1 = P5E_CPU0_P2_TX_C_DN<6> ; 2 = P5E_CPU0_P2_TX_DN<6>
C857  Q_CAP_DIFFBUS  DIFF BUS_0.22UF 6.3V 20% X6S  pkg C0201  page 64 : 1 = P5E_CPU0_P2_TX_C_DP<6> ; 2 = P5E_CPU0_P2_TX_DP<6>
C858  Q_CAP_DIFFBUS  DIFF BUS_0.22UF 6.3V 20% X6S  pkg C0201  page 64 : 1 = P5E_CPU0_P2_TX_C_DN<5> ; 2 = P5E_CPU0_P2_TX_DN<5>
C859  Q_CAP_DIFFBUS  DIFF BUS_0.22UF 6.3V 20% X6S  pkg C0201  page 64 : 1 = P5E_CPU0_P2_TX_C_DP<5> ; 2 = P5E_CPU0_P2_TX_DP<5>
C860  Q_CAP_DIFFBUS  DIFF BUS_0.22UF 6.3V 20% X6S  pkg C0201  page 64 : 1 = P5E_CPU0_P2_TX_C_DN<4> ; 2 = P5E_CPU0_P2_TX_DN<4>
C861  Q_CAP_DIFFBUS  DIFF BUS_0.22UF 6.3V 20% X6S  pkg C0201  page 64 : 1 = P5E_CPU0_P2_TX_C_DP<4> ; 2 = P5E_CPU0_P2_TX_DP<4>
C862  Q_CAP_DIFFBUS  DIFF BUS_0.22UF 6.3V 20% X6S  pkg C0201  page 64 : 1 = P5E_CPU0_P2_TX_C_DN<3> ; 2 = P5E_CPU0_P2_TX_DN<3>
C863  Q_CAP_DIFFBUS  DIFF BUS_0.22UF 6.3V 20% X6S  pkg C0201  page 64 : 1 = P5E_CPU0_P2_TX_C_DP<3> ; 2 = P5E_CPU0_P2_TX_DP<3>
C864  Q_CAP_DIFFBUS  DIFF BUS_0.22UF 6.3V 20% X6S  pkg C0201  page 64 : 1 = P5E_CPU0_P2_TX_C_DN<2> ; 2 = P5E_CPU0_P2_TX_DN<2>
C865  Q_CAP_DIFFBUS  DIFF BUS_0.22UF 6.3V 20% X6S  pkg C0201  page 64 : 1 = P5E_CPU0_P2_TX_C_DP<2> ; 2 = P5E_CPU0_P2_TX_DP<2>
C866  Q_CAP_DIFFBUS  DIFF BUS_0.22UF 6.3V 20% X6S  pkg C0201  page 64 : 1 = P5E_CPU0_P2_TX_C_DN<1> ; 2 = P5E_CPU0_P2_TX_DN<1>
C867  Q_CAP_DIFFBUS  DIFF BUS_0.22UF 6.3V 20% X6S  pkg C0201  page 64 : 1 = P5E_CPU0_P2_TX_C_DP<1> ; 2 = P5E_CPU0_P2_TX_DP<1>
C868  Q_CAP_DIFFBUS  DIFF BUS_0.22UF 6.3V 20% X6S  pkg C0201  page 64 : 1 = P5E_CPU0_P2_TX_C_DN<0> ; 2 = P5E_CPU0_P2_TX_DN<0>
C869  Q_CAP_DIFFBUS  DIFF BUS_0.22UF 6.3V 20% X6S  pkg C0201  page 64 : 1 = P5E_CPU0_P2_TX_C_DP<0> ; 2 = P5E_CPU0_P2_TX_DP<0>
C870  Q_CAP_DIFFBUS  DIFF BUS_0.22UF 6.3V 20% X6S  pkg C0201  page 64 : 1 = P5E_CPU0_P3_TX_C_DN<15> ; 2 = P5E_CPU0_P3_TX_DN<15>
C871  Q_CAP_DIFFBUS  DIFF BUS_0.22UF 6.3V 20% X6S  pkg C0201  page 64 : 1 = P5E_CPU0_P3_TX_C_DP<15> ; 2 = P5E_CPU0_P3_TX_DP<15>
C872  Q_CAP_DIFFBUS  DIFF BUS_0.22UF 6.3V 20% X6S  pkg C0201  page 64 : 1 = P5E_CPU0_P3_TX_C_DN<14> ; 2 = P5E_CPU0_P3_TX_DN<14>
C873  Q_CAP_DIFFBUS  DIFF BUS_0.22UF 6.3V 20% X6S  pkg C0201  page 64 : 1 = P5E_CPU0_P3_TX_C_DP<14> ; 2 = P5E_CPU0_P3_TX_DP<14>
C874  Q_CAP_DIFFBUS  DIFF BUS_0.22UF 6.3V 20% X6S  pkg C0201  page 64 : 1 = P5E_CPU0_P3_TX_C_DN<13> ; 2 = P5E_CPU0_P3_TX_DN<13>
C875  Q_CAP_DIFFBUS  DIFF BUS_0.22UF 6.3V 20% X6S  pkg C0201  page 64 : 1 = P5E_CPU0_P3_TX_C_DP<13> ; 2 = P5E_CPU0_P3_TX_DP<13>
C876  Q_CAP_DIFFBUS  DIFF BUS_0.22UF 6.3V 20% X6S  pkg C0201  page 64 : 1 = P5E_CPU0_P3_TX_C_DN<12> ; 2 = P5E_CPU0_P3_TX_DN<12>
C877  Q_CAP_DIFFBUS  DIFF BUS_0.22UF 6.3V 20% X6S  pkg C0201  page 64 : 1 = P5E_CPU0_P3_TX_C_DP<12> ; 2 = P5E_CPU0_P3_TX_DP<12>
C878  Q_CAP_DIFFBUS  DIFF BUS_0.22UF 6.3V 20% X6S  pkg C0201  page 64 : 1 = P5E_CPU0_P3_TX_C_DN<11> ; 2 = P5E_CPU0_P3_TX_DN<11>
C879  Q_CAP_DIFFBUS  DIFF BUS_0.22UF 6.3V 20% X6S  pkg C0201  page 64 : 1 = P5E_CPU0_P3_TX_C_DP<11> ; 2 = P5E_CPU0_P3_TX_DP<11>
C880  Q_CAP_DIFFBUS  DIFF BUS_0.22UF 6.3V 20% X6S  pkg C0201  page 64 : 1 = P5E_CPU0_P3_TX_C_DN<10> ; 2 = P5E_CPU0_P3_TX_DN<10>
C881  Q_CAP_DIFFBUS  DIFF BUS_0.22UF 6.3V 20% X6S  pkg C0201  page 64 : 1 = P5E_CPU0_P3_TX_C_DP<10> ; 2 = P5E_CPU0_P3_TX_DP<10>
C882  Q_CAP_DIFFBUS  DIFF BUS_0.22UF 6.3V 20% X6S  pkg C0201  page 64 : 1 = P5E_CPU0_P3_TX_C_DN<9> ; 2 = P5E_CPU0_P3_TX_DN<9>
C883  Q_CAP_DIFFBUS  DIFF BUS_0.22UF 6.3V 20% X6S  pkg C0201  page 64 : 1 = P5E_CPU0_P3_TX_C_DP<9> ; 2 = P5E_CPU0_P3_TX_DP<9>
C884  Q_CAP_DIFFBUS  DIFF BUS_0.22UF 6.3V 20% X6S  pkg C0201  page 64 : 1 = P5E_CPU0_P3_TX_C_DN<8> ; 2 = P5E_CPU0_P3_TX_DN<8>
C885  Q_CAP_DIFFBUS  DIFF BUS_0.22UF 6.3V 20% X6S  pkg C0201  page 64 : 1 = P5E_CPU0_P3_TX_C_DP<8> ; 2 = P5E_CPU0_P3_TX_DP<8>
C886  Q_CAP_DIFFBUS  DIFF BUS_0.22UF 6.3V 20% X6S  pkg C0201  page 64 : 1 = P5E_CPU0_P3_TX_C_DN<7> ; 2 = P5E_CPU0_P3_TX_DN<7>
C887  Q_CAP_DIFFBUS  DIFF BUS_0.22UF 6.3V 20% X6S  pkg C0201  page 64 : 1 = P5E_CPU0_P3_TX_C_DP<7> ; 2 = P5E_CPU0_P3_TX_DP<7>
C888  Q_CAP_DIFFBUS  DIFF BUS_0.22UF 6.3V 20% X6S  pkg C0201  page 64 : 1 = P5E_CPU0_P3_TX_C_DN<6> ; 2 = P5E_CPU0_P3_TX_DN<6>
C889  Q_CAP_DIFFBUS  DIFF BUS_0.22UF 6.3V 20% X6S  pkg C0201  page 64 : 1 = P5E_CPU0_P3_TX_C_DP<6> ; 2 = P5E_CPU0_P3_TX_DP<6>
C890  Q_CAP_DIFFBUS  DIFF BUS_0.22UF 6.3V 20% X6S  pkg C0201  page 64 : 1 = P5E_CPU0_P3_TX_C_DN<5> ; 2 = P5E_CPU0_P3_TX_DN<5>
C891  Q_CAP_DIFFBUS  DIFF BUS_0.22UF 6.3V 20% X6S  pkg C0201  page 64 : 1 = P5E_CPU0_P3_TX_C_DP<5> ; 2 = P5E_CPU0_P3_TX_DP<5>
C892  Q_CAP_DIFFBUS  DIFF BUS_0.22UF 6.3V 20% X6S  pkg C0201  page 64 : 1 = P5E_CPU0_P3_TX_C_DN<4> ; 2 = P5E_CPU0_P3_TX_DN<4>
C893  Q_CAP_DIFFBUS  DIFF BUS_0.22UF 6.3V 20% X6S  pkg C0201  page 64 : 1 = P5E_CPU0_P3_TX_C_DP<4> ; 2 = P5E_CPU0_P3_TX_DP<4>
C894  Q_CAP_DIFFBUS  DIFF BUS_0.22UF 6.3V 20% X6S  pkg C0201  page 64 : 1 = P5E_CPU0_P3_TX_C_DN<3> ; 2 = P5E_CPU0_P3_TX_DN<3>
C895  Q_CAP_DIFFBUS  DIFF BUS_0.22UF 6.3V 20% X6S  pkg C0201  page 64 : 1 = P5E_CPU0_P3_TX_C_DP<3> ; 2 = P5E_CPU0_P3_TX_DP<3>
C896  Q_CAP_DIFFBUS  DIFF BUS_0.22UF 6.3V 20% X6S  pkg C0201  page 64 : 1 = P5E_CPU0_P3_TX_C_DN<2> ; 2 = P5E_CPU0_P3_TX_DN<2>
C897  Q_CAP_DIFFBUS  DIFF BUS_0.22UF 6.3V 20% X6S  pkg C0201  page 64 : 1 = P5E_CPU0_P3_TX_C_DP<2> ; 2 = P5E_CPU0_P3_TX_DP<2>
C898  Q_CAP_DIFFBUS  DIFF BUS_0.22UF 6.3V 20% X6S  pkg C0201  page 64 : 1 = P5E_CPU0_P3_TX_C_DN<1> ; 2 = P5E_CPU0_P3_TX_DN<1>
C899  Q_CAP_DIFFBUS  DIFF BUS_0.22UF 6.3V 20% X6S  pkg C0201  page 64 : 1 = P5E_CPU0_P3_TX_C_DP<1> ; 2 = P5E_CPU0_P3_TX_DP<1>
C900  Q_CAP_DIFFBUS  DIFF BUS_0.22UF 6.3V 20% X6S  pkg C0201  page 64 : 1 = P5E_CPU0_P3_TX_C_DN<0> ; 2 = P5E_CPU0_P3_TX_DN<0>
C901  Q_CAP_DIFFBUS  DIFF BUS_0.22UF 6.3V 20% X6S  pkg C0201  page 64 : 1 = P5E_CPU0_P3_TX_C_DP<0> ; 2 = P5E_CPU0_P3_TX_DP<0>
C902  Q_CAP_DIFFBUS  DIFF BUS_0.22UF 6.3V 20% X6S  pkg C0201  page 63 : 1 = P5E_CPU0_P0_TX_C_DN<15> ; 2 = P5E_CPU0_P0_TX_DN<15>
C903  Q_CAP_DIFFBUS  DIFF BUS_0.22UF 6.3V 20% X6S  pkg C0201  page 63 : 1 = P5E_CPU0_P0_TX_C_DP<15> ; 2 = P5E_CPU0_P0_TX_DP<15>
C904  Q_CAP_DIFFBUS  DIFF BUS_0.22UF 6.3V 20% X6S  pkg C0201  page 63 : 1 = P5E_CPU0_P0_TX_C_DN<14> ; 2 = P5E_CPU0_P0_TX_DN<14>
C905  Q_CAP_DIFFBUS  DIFF BUS_0.22UF 6.3V 20% X6S  pkg C0201  page 63 : 1 = P5E_CPU0_P0_TX_C_DP<14> ; 2 = P5E_CPU0_P0_TX_DP<14>
C906  Q_CAP_DIFFBUS  DIFF BUS_0.22UF 6.3V 20% X6S  pkg C0201  page 63 : 1 = P5E_CPU0_P0_TX_C_DN<13> ; 2 = P5E_CPU0_P0_TX_DN<13>
C907  Q_CAP_DIFFBUS  DIFF BUS_0.22UF 6.3V 20% X6S  pkg C0201  page 63 : 1 = P5E_CPU0_P0_TX_C_DP<13> ; 2 = P5E_CPU0_P0_TX_DP<13>
C908  Q_CAP_DIFFBUS  DIFF BUS_0.22UF 6.3V 20% X6S  pkg C0201  page 63 : 1 = P5E_CPU0_P0_TX_C_DN<12> ; 2 = P5E_CPU0_P0_TX_DN<12>
C909  Q_CAP_DIFFBUS  DIFF BUS_0.22UF 6.3V 20% X6S  pkg C0201  page 63 : 1 = P5E_CPU0_P0_TX_C_DP<12> ; 2 = P5E_CPU0_P0_TX_DP<12>
C910  Q_CAP_DIFFBUS  DIFF BUS_0.22UF 6.3V 20% X6S  pkg C0201  page 63 : 1 = P5E_CPU0_P0_TX_C_DN<11> ; 2 = P5E_CPU0_P0_TX_DN<11>
